# S9S_MB_2U (Grand Teton) — schematic netlist excerpt (pin names and nets, part order shuffled) for the footprints in the layout excerpt that follows; sources: Cadence DE-HDL packaged netlist, KiCad conversion of 03242023_DA0F0TMBIJ0_F0T_Motherboard_J_brd_V01_OCP.brd

R3293  Q_RES  4.7K 1% EMPTY  pkg 0402LF  page 166 : A = FM_P2E_MODE ; B = GND
C2347  Q_CAP  0.1UF 25V 10% X7R  pkg 0402  page 164 : A = P3V3_AUX ; B = GND

(kicad_pcb
	(version 20260206)
	(generator "pcbnew")
	(generator_version "10.0")
	(general
		(thickness 1.6)
		(legacy_teardrops no)
	)
	(paper "A4")
	(title_block
		(title "03242023_DA0F0TMBIJ0_F0T_Motherboard_J_brd_V01_OCP.brd")
		(comment 1 "Grand Teton / footprints 3926-3927 of 6105")
	)
	(layers
		(0 "F.Cu" signal "TOP")
		(4 "In1.Cu" signal "GND")
		(6 "In2.Cu" signal "IN1")
		(8 "In3.Cu" signal "GND1")
		(10 "In4.Cu" signal "IN2")
		(12 "In5.Cu" signal "GND2")
		(14 "In6.Cu" signal "IN3")
		(16 "In7.Cu" signal "GND3")
		(18 "In8.Cu" signal "VCC")
		(20 "In9.Cu" signal "VCC1")
		(22 "In10.Cu" signal "GND4")
		(24 "In11.Cu" signal "IN4")
		(26 "In12.Cu" signal "GND5")
		(28 "In13.Cu" signal "IN5")
		(30 "In14.Cu" signal "GND6")
		(32 "In15.Cu" signal "IN6")
		(34 "In16.Cu" signal "GND7")
		(2 "B.Cu" signal "BOTTOM")
		(9 "F.Adhes" user "F.Adhesive")
		(11 "B.Adhes" user "B.Adhesive")
		(13 "F.Paste" user "Package Geometry/Pastemask Top")
		(15 "B.Paste" user "Package Geometry/Pastemask Bottom")
		(5 "F.SilkS" user "Ref Des/Silkscreen Top")
		(7 "B.SilkS" user "Ref Des/Silkscreen Bottom")
		(1 "F.Mask" user "Board Geometry/Soldermask Top")
		(3 "B.Mask" user "Board Geometry/Soldermask Bottom")
		(17 "Dwgs.User" user "User.Drawings")
		(19 "Cmts.User" user "User.Comments")
		(21 "Eco1.User" user "User.Eco1")
		(23 "Eco2.User" user "User.Eco2")
		(25 "Edge.Cuts" user "Board Geometry/Outline")
		(27 "Margin" user)
		(31 "F.CrtYd" user "Package Geometry/Place Bound Top")
		(29 "B.CrtYd" user "Package Geometry/Place Bound Bottom")
		(35 "F.Fab" user "Ref Des/Assembly Top")
		(33 "B.Fab" user "Ref Des/Assembly Bottom")
	)
	(footprint ""
		(layer "F.Cu")
		(at 15.436596 -387.119876 180)
		(property "Reference" "R3293"
			(at 0 0 180)
			(layer "F.SilkS")
			(hide yes)
			(effects
				(font
					(size 1.27 1.27)
				)
			)
		)
		(property "Value" ""
			(at 0 0 180)
			(layer "F.Fab")
			(effects
				(font
					(size 1.27 1.27)
				)
			)
		)
		(duplicate_pad_numbers_are_jumpers no)
		(fp_line
			(start 0.7874 0.4064)
			(end -0.7874 0.4064)
			(stroke
				(width 0.1524)
				(type default)
			)
			(layer "F.SilkS")
		)
		(fp_line
			(start 0.7874 -0.4064)
			(end 0.7874 0.4064)
			(stroke
				(width 0.1524)
				(type default)
			)
			(layer "F.SilkS")
		)
		(fp_line
			(start -0.7874 0.4064)
			(end -0.7874 -0.4064)
			(stroke
				(width 0.1524)
				(type default)
			)
			(layer "F.SilkS")
		)
		(fp_line
			(start -0.7874 -0.4064)
			(end 0.7874 -0.4064)
			(stroke
				(width 0.1524)
				(type default)
			)
			(layer "F.SilkS")
		)
		(fp_line
			(start 0.67945 0.3048)
			(end 0.120396 0.3048)
			(stroke
				(width 0.1)
				(type default)
			)
			(layer "F.Fab")
		)
		(fp_line
			(start 0.67945 -0.3048)
			(end 0.67945 0.3048)
			(stroke
				(width 0.1)
				(type default)
			)
			(layer "F.Fab")
		)
		(fp_line
			(start 0.12065 -0.2794)
			(end 0.12065 -0.3048)
			(stroke
				(width 0.1)
				(type default)
			)
			(layer "F.Fab")
		)
		(fp_line
			(start 0.12065 -0.3048)
			(end 0.67945 -0.3048)
			(stroke
				(width 0.1)
				(type default)
			)
			(layer "F.Fab")
		)
		(fp_line
			(start 0.120396 0.3048)
			(end 0.120396 0.2794)
			(stroke
				(width 0.1)
				(type default)
			)
			(layer "F.Fab")
		)
		(fp_line
			(start 0.120396 0.2794)
			(end -0.12065 0.2794)
			(stroke
				(width 0.1)
				(type default)
			)
			(layer "F.Fab")
		)
		(fp_line
			(start -0.12065 0.3048)
			(end -0.67945 0.3048)
			(stroke
				(width 0.1)
				(type default)
			)
			(layer "F.Fab")
		)
		(fp_line
			(start -0.12065 0.2794)
			(end -0.12065 0.3048)
			(stroke
				(width 0.1)
				(type default)
			)
			(layer "F.Fab")
		)
		(fp_line
			(start -0.12065 -0.2794)
			(end 0.12065 -0.2794)
			(stroke
				(width 0.1)
				(type default)
			)
			(layer "F.Fab")
		)
		(fp_line
			(start -0.12065 -0.305054)
			(end -0.12065 -0.2794)
			(stroke
				(width 0.1)
				(type default)
			)
			(layer "F.Fab")
		)
		(fp_line
			(start -0.67945 0.3048)
			(end -0.67945 -0.305054)
			(stroke
				(width 0.1)
				(type default)
			)
			(layer "F.Fab")
		)
		(fp_line
			(start -0.67945 -0.305054)
			(end -0.12065 -0.305054)
			(stroke
				(width 0.1)
				(type default)
			)
			(layer "F.Fab")
		)
		(pad "1" smd circle
			(at -0.40005 0 180)
			(size 0 0)
			(layers "F.Cu" "F.Mask" "F.Paste")
			(net "FM_P2E_MODE")
		)
		(pad "2" smd circle
			(at 0.40005 0 180)
			(size 0 0)
			(layers "F.Cu" "F.Mask" "F.Paste")
			(net "GND")
		)
	)
	(footprint ""
		(layer "F.Cu")
		(at 81.8896 -41.036748 180)
		(property "Reference" "C2347"
			(at 0 0 180)
			(layer "F.SilkS")
			(hide yes)
			(effects
				(font
					(size 1.27 1.27)
				)
			)
		)
		(property "Value" ""
			(at 0 0 180)
			(layer "F.Fab")
			(effects
				(font
					(size 1.27 1.27)
				)
			)
		)
		(duplicate_pad_numbers_are_jumpers no)
		(fp_line
			(start 0.7874 0.4064)
			(end -0.7874 0.4064)
			(stroke
				(width 0.1524)
				(type default)
			)
			(layer "F.SilkS")
		)
		(fp_line
			(start 0.7874 -0.4064)
			(end 0.7874 0.4064)
			(stroke
				(width 0.1524)
				(type default)
			)
			(layer "F.SilkS")
		)
		(fp_line
			(start -0.7874 0.4064)
			(end -0.7874 -0.4064)
			(stroke
				(width 0.1524)
				(type default)
			)
			(layer "F.SilkS")
		)
		(fp_line
			(start -0.7874 -0.4064)
			(end 0.7874 -0.4064)
			(stroke
				(width 0.1524)
				(type default)
			)
			(layer "F.SilkS")
		)
		(fp_line
			(start 0.67945 0.3048)
			(end 0.120396 0.3048)
			(stroke
				(width 0.1)
				(type default)
			)
			(layer "F.Fab")
		)
		(fp_line
			(start 0.67945 -0.3048)
			(end 0.67945 0.3048)
			(stroke
				(width 0.1)
				(type default)
			)
			(layer "F.Fab")
		)
		(fp_line
			(start 0.12065 -0.2794)
			(end 0.12065 -0.3048)
			(stroke
				(width 0.1)
				(type default)
			)
			(layer "F.Fab")
		)
		(fp_line
			(start 0.12065 -0.3048)
			(end 0.67945 -0.3048)
			(stroke
				(width 0.1)
				(type default)
			)
			(layer "F.Fab")
		)
		(fp_line
			(start 0.120396 0.3048)
			(end 0.120396 0.2794)
			(stroke
				(width 0.1)
				(type default)
			)
			(layer "F.Fab")
		)
		(fp_line
			(start 0.120396 0.2794)
			(end -0.12065 0.2794)
			(stroke
				(width 0.1)
				(type default)
			)
			(layer "F.Fab")
		)
		(fp_line
			(start -0.12065 0.3048)
			(end -0.67945 0.3048)
			(stroke
				(width 0.1)
				(type default)
			)
			(layer "F.Fab")
		)
		(fp_line
			(start -0.12065 0.2794)
			(end -0.12065 0.3048)
			(stroke
				(width 0.1)
				(type default)
			)
			(layer "F.Fab")
		)
		(fp_line
			(start -0.12065 -0.2794)
			(end 0.12065 -0.2794)
			(stroke
				(width 0.1)
				(type default)
			)
			(layer "F.Fab")
		)
		(fp_line
			(start -0.12065 -0.305054)
			(end -0.12065 -0.2794)
			(stroke
				(width 0.1)
				(type default)
			)
			(layer "F.Fab")
		)
		(fp_line
			(start -0.67945 0.3048)
			(end -0.67945 -0.305054)
			(stroke
				(width 0.1)
				(type default)
			)
			(layer "F.Fab")
		)
		(fp_line
			(start -0.67945 -0.305054)
			(end -0.12065 -0.305054)
			(stroke
				(width 0.1)
				(type default)
			)
			(layer "F.Fab")
		)
		(pad "1" smd circle
			(at -0.40005 0 180)
			(size 0 0)
			(layers "F.Cu" "F.Mask" "F.Paste")
			(net "P3V3_AUX")
		)
		(pad "2" smd circle
			(at 0.40005 0 180)
			(size 0 0)
			(layers "F.Cu" "F.Mask" "F.Paste")
			(net "GND")
		)
	)
)
